(kicad_pcb
	(version 20260206)
	(generator "pcbnew")
	(generator_version "10.0")
	(general
		(thickness 1.6)
		(legacy_teardrops no)
	)
	(paper "A4")
	(title_block
		(title "01162023_DA0F0TEBIF0_F0T_Expander_BD_F_brd_V02_OCP.brd")
		(comment 1 "Grand Teton / footprints 288-289 of 9728")
	)
	(layers
		(0 "F.Cu" signal "TOP")
		(4 "In1.Cu" signal "GND")
		(6 "In2.Cu" signal "VCC")
		(8 "In3.Cu" signal "VCC1")
		(10 "In4.Cu" signal "GND1")
		(12 "In5.Cu" signal "IN1")
		(14 "In6.Cu" signal "GND2")
		(16 "In7.Cu" signal "IN2")
		(18 "In8.Cu" signal "GND3")
		(20 "In9.Cu" signal "IN3")
		(22 "In10.Cu" signal "GND4")
		(24 "In11.Cu" signal "IN4")
		(26 "In12.Cu" signal "GND5")
		(28 "In13.Cu" signal "IN5")
		(30 "In14.Cu" signal "GND6")
		(32 "In15.Cu" signal "IN6")
		(34 "In16.Cu" signal "GND7")
		(2 "B.Cu" signal "BOTTOM")
		(9 "F.Adhes" user "F.Adhesive")
		(11 "B.Adhes" user "B.Adhesive")
		(13 "F.Paste" user "Package Geometry/Pastemask Top")
		(15 "B.Paste" user "Package Geometry/Pastemask Bottom")
		(5 "F.SilkS" user "Ref Des/Silkscreen Top")
		(7 "B.SilkS" user "Ref Des/Silkscreen Bottom")
		(1 "F.Mask" user "Board Geometry/Soldermask Top")
		(3 "B.Mask" user "Board Geometry/Soldermask Bottom")
		(17 "Dwgs.User" user "User.Drawings")
		(19 "Cmts.User" user "User.Comments")
		(21 "Eco1.User" user "User.Eco1")
		(23 "Eco2.User" user "User.Eco2")
		(25 "Edge.Cuts" user "Board Geometry/Outline")
		(27 "Margin" user)
		(31 "F.CrtYd" user "Package Geometry/Place Bound Top")
		(29 "B.CrtYd" user "Package Geometry/Place Bound Bottom")
		(35 "F.Fab" user "Ref Des/Assembly Top")
		(33 "B.Fab" user "Ref Des/Assembly Bottom")
	)
	(footprint ""
		(layer "F.Cu")
		(at 170.59529 -35.48253)
		(property "Reference" "U389"
			(at -2.54762 1.09093 90)
			(unlocked yes)
			(layer "F.SilkS")
			(effects
				(font
					(size 0.7874 0.5842)
					(thickness 0.1524)
				)
				(justify left)
			)
		)
		(property "Value" ""
			(at 0 0 0)
			(layer "F.Fab")
			(effects
				(font
					(size 1.27 1.27)
				)
			)
		)
		(duplicate_pad_numbers_are_jumpers no)
		(fp_line
			(start -1.3462 -1.1938)
			(end -1.3462 1.1684)
			(stroke
				(width 0.1524)
				(type default)
			)
			(layer "F.SilkS")
		)
		(fp_line
			(start -1.3462 1.1938)
			(end 1.3462 1.1938)
			(stroke
				(width 0.1524)
				(type default)
			)
			(layer "F.SilkS")
		)
		(fp_line
			(start 1.3462 -1.1938)
			(end -1.3462 -1.1938)
			(stroke
				(width 0.1524)
				(type default)
			)
			(layer "F.SilkS")
		)
		(fp_line
			(start 1.3462 1.1938)
			(end 1.3462 -1.1938)
			(stroke
				(width 0.1524)
				(type default)
			)
			(layer "F.SilkS")
		)
		(fp_poly
			(pts
				(xy -1.447038 -0.760476) (xy -2.052066 -0.457962) (xy -2.052066 -1.06299)
			)
			(stroke
				(width 0)
				(type default)
			)
			(fill yes)
			(layer "F.SilkS")
		)
		(fp_line
			(start -0.674878 -1.124966)
			(end -0.674878 1.124966)
			(stroke
				(width 0.1)
				(type default)
			)
			(layer "F.Fab")
		)
		(fp_line
			(start -0.674878 1.124966)
			(end 0.674878 1.124966)
			(stroke
				(width 0.1)
				(type default)
			)
			(layer "F.Fab")
		)
		(fp_line
			(start 0.674878 -1.124966)
			(end -0.674878 -1.124966)
			(stroke
				(width 0.1)
				(type default)
			)
			(layer "F.Fab")
		)
		(fp_line
			(start 0.674878 1.124966)
			(end 0.674878 -1.124966)
			(stroke
				(width 0.1)
				(type default)
			)
			(layer "F.Fab")
		)
		(fp_poly
			(pts
				(xy -1.447038 -0.760476) (xy -2.052066 -0.457962) (xy -2.052066 -1.06299)
			)
			(stroke
				(width 0)
				(type default)
			)
			(fill yes)
			(layer "F.Fab")
		)
		(pad "1" smd rect
			(at -0.899922 -0.750062)
			(size 0.6096 0.6096)
			(layers "F.Cu" "F.Mask" "F.Paste")
			(net "PWRGD_P3V3_SSD6_R")
		)
		(pad "2" smd rect
			(at -0.899922 0 90)
			(size 0.4064 0.6096)
			(layers "F.Cu" "F.Mask" "F.Paste")
			(net "RST_SMB_SSD6_N")
		)
		(pad "3" smd rect
			(at -0.899922 0.750062)
			(size 0.6096 0.6096)
			(layers "F.Cu" "F.Mask" "F.Paste")
			(net "GND")
		)
		(pad "4" smd rect
			(at 0.899922 0.750062)
			(size 0.6096 0.6096)
			(layers "F.Cu" "F.Mask" "F.Paste")
			(net "RST_SMB_SSD6_ISO_N")
		)
		(pad "5" smd rect
			(at 0.899922 -0.750062)
			(size 0.6096 0.6096)
			(layers "F.Cu" "F.Mask" "F.Paste")
			(net "P3V3_AUX")
		)
	)
	(footprint ""
		(layer "F.Cu")
		(at 248.241058 -115.695476)
		(property "Reference" "PU119"
			(at -1.048258 2.209546 0)
			(unlocked yes)
			(layer "F.SilkS")
			(effects
				(font
					(size 0.7874 0.5842)
					(thickness 0.1524)
				)
			)
		)
		(property "Value" ""
			(at 0 0 0)
			(layer "F.Fab")
			(effects
				(font
					(size 1.27 1.27)
				)
			)
		)
		(duplicate_pad_numbers_are_jumpers no)
		(fp_line
			(start -1.239774 -1.495298)
			(end 1.239774 -1.495298)
			(stroke
				(width 0.1524)
				(type default)
			)
			(layer "F.SilkS")
		)
		(fp_line
			(start -1.239774 1.495298)
			(end -1.239774 -1.495298)
			(stroke
				(width 0.1524)
				(type default)
			)
			(layer "F.SilkS")
		)
		(fp_line
			(start 1.239774 -1.495298)
			(end 1.239774 1.495298)
			(stroke
				(width 0.1524)
				(type default)
			)
			(layer "F.SilkS")
		)
		(fp_line
			(start 1.239774 1.495298)
			(end -1.239774 1.495298)
			(stroke
				(width 0.1524)
				(type default)
			)
			(layer "F.SilkS")
		)
		(fp_poly
			(pts
				(xy -1.795272 -1.757934) (xy -2.513838 -1.039622) (xy -1.436116 -0.680466)
			)
			(stroke
				(width 0)
				(type default)
			)
			(fill yes)
			(layer "F.SilkS")
		)
		(fp_line
			(start -0.8001 -1.050036)
			(end 0.8001 -1.050036)
			(stroke
				(width 0.1)
				(type default)
			)
			(layer "F.Fab")
		)
		(fp_line
			(start -0.8001 1.050036)
			(end -0.8001 -1.050036)
			(stroke
				(width 0.1)
				(type default)
			)
			(layer "F.Fab")
		)
		(fp_line
			(start 0.8001 -1.050036)
			(end 0.8001 1.050036)
			(stroke
				(width 0.1)
				(type default)
			)
			(layer "F.Fab")
		)
		(fp_line
			(start 0.8001 1.050036)
			(end -0.8001 1.050036)
			(stroke
				(width 0.1)
				(type default)
			)
			(layer "F.Fab")
		)
		(fp_poly
			(pts
				(xy -2.458974 -0.508) (xy -2.458974 0.508) (xy -1.442974 0)
			)
			(stroke
				(width 0)
				(type default)
			)
			(fill yes)
			(layer "F.Fab")
		)
		(pad "1_2" smd circle
			(at -0.374904 0 90)
			(size 0 0)
			(layers "F.Cu" "F.Mask" "F.Paste")
			(net "P3V3_AUX")
		)
		(pad "3" smd rect
			(at -0.499872 0.999998)
			(size 0.254 0.7112)
			(layers "F.Cu" "F.Mask" "F.Paste")
			(net "GND")
		)
		(pad "4" smd rect
			(at 0 0.999998)
			(size 0.254 0.7112)
			(layers "F.Cu" "F.Mask" "F.Paste")
			(net "P3V3_NIC4_CO_ILIMIT")
		)
		(pad "5" smd rect
			(at 0.499872 0.999998)
			(size 0.254 0.7112)
			(layers "F.Cu" "F.Mask" "F.Paste")
			(net "P3V3_NIC4_CO_MODE")
		)
		(pad "6_7" smd circle
			(at 0.374904 0 270)
			(size 0 0)
			(layers "F.Cu" "F.Mask" "F.Paste")
			(net "P3V3_NIC4")
		)
		(pad "8" smd rect
			(at 0.499872 -0.999998)
			(size 0.254 0.7112)
			(layers "F.Cu" "F.Mask" "F.Paste")
			(net "P3V3_NIC4_CO_GATE")
		)
		(pad "9" smd rect
			(at 0 -0.999998)
			(size 0.254 0.7112)
			(layers "F.Cu" "F.Mask" "F.Paste")
			(net "P3V3_NIC4_CO_EN")
		)
		(pad "10" smd rect
			(at -0.499872 -0.999998)
			(size 0.254 0.7112)
			(layers "F.Cu" "F.Mask" "F.Paste")
			(net "P3V3_NIC4_CO_DV_DT")
		)
	)
)
